(kicad_pcb
	(version 20241229)
	(generator "pcbnew")
	(generator_version "9.0")
	(general
		(thickness 1.294)
		(legacy_teardrops no)
	)
	(paper "A3")
	(title_block
		(title "Kintex 410T devboard")
		(date "2024-04-03")
		(rev "1.1.2")
		(comment 9 "footprints 975-975 of 975")
	)
	(layers
		(0 "F.Cu" mixed)
		(4 "In1.Cu" power)
		(6 "In2.Cu" power)
		(8 "In3.Cu" mixed)
		(10 "In4.Cu" power)
		(12 "In5.Cu" mixed)
		(14 "In6.Cu" power)
		(16 "In7.Cu" mixed)
		(18 "In8.Cu" power)
		(2 "B.Cu" mixed)
		(9 "F.Adhes" user "F.Adhesive")
		(11 "B.Adhes" user "B.Adhesive")
		(13 "F.Paste" user)
		(15 "B.Paste" user)
		(5 "F.SilkS" user "F.Silkscreen")
		(7 "B.SilkS" user "B.Silkscreen")
		(1 "F.Mask" user)
		(3 "B.Mask" user)
		(17 "Dwgs.User" user "User.Drawings")
		(19 "Cmts.User" user "User.Comments")
		(21 "Eco1.User" user "User.Eco1")
		(23 "Eco2.User" user "User.Eco2")
		(25 "Edge.Cuts" user)
		(27 "Margin" user)
		(31 "F.CrtYd" user "F.Courtyard")
		(29 "B.CrtYd" user "B.Courtyard")
		(35 "F.Fab" user)
		(33 "B.Fab" user)
	)
	(footprint "antmicro-footprints:R_0402_1005Metric"
		(layer "B.Cu")
		(at 162.1625 175.3 90)
		(descr "Resistor SMD 0402")
		(tags "resistor SMD 0402")
		(property "Reference" "R310"
			(at -0.7 0.3875 270)
			(layer "B.SilkS")
			(effects
				(font
					(size 0.7 0.7)
					(thickness 0.15)
				)
				(justify left bottom mirror)
			)
		)
		(property "Value" "R_0R_0402"
			(at 0 -1.4 270)
			(layer "B.Fab")
			(effects
				(font
					(size 0.7 0.7)
					(thickness 0.15)
				)
				(justify left bottom mirror)
			)
		)
		(property "Description" "SMD Chip Resistor, Jumper, 0 ohm, 100 mW, 0402 [1005 Metric], Thick Film, General Purpose"
			(at 0 0 90)
			(layer "F.Fab")
			(hide yes)
			(effects
				(font
					(size 1.27 1.27)
					(thickness 0.15)
				)
			)
		)
		(property "Author" "Antmicro"
			(at 337.4625 13.1375 0)
			(layer "B.Fab")
			(hide yes)
			(effects
				(font
					(size 1 1)
					(thickness 0.15)
				)
				(justify mirror)
			)
		)
		(property "Current" "1A"
			(at 337.4625 13.1375 0)
			(layer "B.Fab")
			(hide yes)
			(effects
				(font
					(size 1 1)
					(thickness 0.15)
				)
				(justify mirror)
			)
		)
		(property "DNP" "DNP"
			(at 337.4625 13.1375 0)
			(layer "B.Fab")
			(hide yes)
			(effects
				(font
					(size 1 1)
					(thickness 0.15)
				)
				(justify mirror)
			)
		)
		(property "License" "Apache-2.0"
			(at 337.4625 13.1375 0)
			(layer "B.Fab")
			(hide yes)
			(effects
				(font
					(size 1 1)
					(thickness 0.15)
				)
				(justify mirror)
			)
		)
		(property "MPN" "ERJ2GE0R00X"
			(at 337.4625 13.1375 0)
			(layer "B.Fab")
			(hide yes)
			(effects
				(font
					(size 1 1)
					(thickness 0.15)
				)
				(justify mirror)
			)
		)
		(property "Manufacturer" "Panasonic"
			(at 337.4625 13.1375 0)
			(layer "B.Fab")
			(hide yes)
			(effects
				(font
					(size 1 1)
					(thickness 0.15)
				)
				(justify mirror)
			)
		)
		(property "Tolerance" ""
			(at 337.4625 13.1375 0)
			(layer "B.Fab")
			(hide yes)
			(effects
				(font
					(size 1 1)
					(thickness 0.15)
				)
				(justify mirror)
			)
		)
		(property "Val" "0R"
			(at 337.4625 13.1375 0)
			(layer "B.Fab")
			(hide yes)
			(effects
				(font
					(size 1 1)
					(thickness 0.15)
				)
				(justify mirror)
			)
		)
		(property "dnp" ""
			(at 337.4625 13.1375 0)
			(layer "B.Fab")
			(hide yes)
			(effects
				(font
					(size 1 1)
					(thickness 0.15)
				)
				(justify mirror)
			)
		)
		(property "exclude_from_bom" ""
			(at 337.4625 13.1375 0)
			(layer "B.Fab")
			(hide yes)
			(effects
				(font
					(size 1 1)
					(thickness 0.15)
				)
				(justify mirror)
			)
		)
		(sheetname "DC-DC Converters")
		(sheetfile "dc-dc.kicad_sch")
		(attr smd exclude_from_bom)
		(fp_rect
			(start -0.925 0.47)
			(end 0.925 -0.47)
			(stroke
				(width 0.05)
				(type default)
			)
			(fill no)
			(layer "B.CrtYd")
		)
		(fp_rect
			(start -0.5 0.25)
			(end 0.5 -0.25)
			(stroke
				(width 0.15)
				(type solid)
			)
			(fill no)
			(layer "B.Fab")
		)
		(pad "1" smd roundrect
			(at -0.48 0 90)
			(size 0.59 0.64)
			(layers "B.Cu" "B.Mask" "B.Paste")
			(roundrect_rratio 0.25)
			(net 1225 "/DC-DC Converters/SENSE_1V2_N")
			(pintype "passive")
		)
		(pad "2" smd roundrect
			(at 0.48 0 90)
			(size 0.59 0.64)
			(layers "B.Cu" "B.Mask" "B.Paste")
			(roundrect_rratio 0.25)
			(net 962 "/DC-DC Converters/FB3")
			(pintype "passive")
		)
	)
)
